# BASEBOARD_FAB2 (Tioga Pass) — schematic netlist excerpt (pin names and nets, part order shuffled) for the footprints in the layout excerpt that follows; sources: Cadence DE-HDL packaged netlist, KiCad conversion of Wiwynn_Tioga_Pass_MB.brd

R25W177  RES  1.00K 1% CHIP  pkg 0402  page 254 : A = P3V3_STBY ; B = BMC_PREQ_BUF_N
C4G17  CAP_A  0.01UF 25V 10% X7R  pkg 0402V  page 98 : A = M_C_CPU_VREF ; B = GND
R7A14  RES  10.0 1% CHIP  pkg 0402  page 236 : A = VSENSE_PVNN_PCH_STBY_FPK ; B = VSENSE_PVNN_PCH_STBY_AVSP

(kicad_pcb
	(version 20260206)
	(generator "pcbnew")
	(generator_version "10.0")
	(general
		(thickness 1.6)
		(legacy_teardrops no)
	)
	(paper "A4")
	(title_block
		(title "Wiwynn_Tioga_Pass_MB.brd")
		(comment 1 "Tioga Pass / footprints 994-996 of 4770")
	)
	(layers
		(0 "F.Cu" signal "TOP")
		(4 "In1.Cu" signal "L2GND")
		(6 "In2.Cu" signal "L3")
		(8 "In3.Cu" signal "L4GND")
		(10 "In4.Cu" signal "L5")
		(12 "In5.Cu" signal "L6GND")
		(14 "In6.Cu" signal "L7VCC")
		(16 "In7.Cu" signal "L8VCC")
		(18 "In8.Cu" signal "L9GND")
		(20 "In9.Cu" signal "L10")
		(22 "In10.Cu" signal "L11GND")
		(24 "In11.Cu" signal "L12")
		(26 "In12.Cu" signal "L13GND")
		(2 "B.Cu" signal "BOTTOM")
		(9 "F.Adhes" user "F.Adhesive")
		(11 "B.Adhes" user "B.Adhesive")
		(13 "F.Paste" user "Package Geometry/Pastemask Top")
		(15 "B.Paste" user "Package Geometry/Pastemask Bottom")
		(5 "F.SilkS" user "Ref Des/Silkscreen Top")
		(7 "B.SilkS" user "Ref Des/Silkscreen Bottom")
		(1 "F.Mask" user "Board Geometry/Soldermask Top")
		(3 "B.Mask" user "Board Geometry/Soldermask Bottom")
		(17 "Dwgs.User" user "User.Drawings")
		(19 "Cmts.User" user "User.Comments")
		(21 "Eco1.User" user "User.Eco1")
		(23 "Eco2.User" user "User.Eco2")
		(25 "Edge.Cuts" user "Board Geometry/Outline")
		(27 "Margin" user)
		(31 "F.CrtYd" user "Package Geometry/Place Bound Top")
		(29 "B.CrtYd" user "Package Geometry/Place Bound Bottom")
		(35 "F.Fab" user "Ref Des/Assembly Top")
		(33 "B.Fab" user "Ref Des/Assembly Bottom")
	)
	(footprint ""
		(layer "F.Cu")
		(at 191.897 -3.7465)
		(property "Reference" "C4G17"
			(at 0 0 0)
			(layer "F.SilkS")
			(hide yes)
			(effects
				(font
					(size 1.27 1.27)
				)
			)
		)
		(property "Value" ""
			(at 0 0 0)
			(layer "F.Fab")
			(effects
				(font
					(size 1.27 1.27)
				)
			)
		)
		(duplicate_pad_numbers_are_jumpers no)
		(fp_poly
			(pts
				(xy 0.3048 -0.1016) (xy 0.3048 0.9906) (xy -0.3048 0.9906) (xy -0.3048 -0.1016)
			)
			(stroke
				(width 0)
				(type default)
			)
			(fill no)
			(layer "F.CrtYd")
		)
		(fp_line
			(start -0.3048 -0.1016)
			(end -0.3048 0.9906)
			(stroke
				(width 0.1)
				(type default)
			)
			(layer "F.Fab")
		)
		(fp_line
			(start -0.3048 0.9906)
			(end 0.3048 0.9906)
			(stroke
				(width 0.1)
				(type default)
			)
			(layer "F.Fab")
		)
		(fp_line
			(start 0.3048 -0.1016)
			(end -0.3048 -0.1016)
			(stroke
				(width 0.1)
				(type default)
			)
			(layer "F.Fab")
		)
		(fp_line
			(start 0.3048 0.9906)
			(end 0.3048 -0.1016)
			(stroke
				(width 0.1)
				(type default)
			)
			(layer "F.Fab")
		)
		(pad "1" smd rect
			(at 0 0)
			(size 0.508 0.508)
			(layers "F.Cu" "F.Mask" "F.Paste")
			(net "M_C_CPU_VREF")
		)
		(pad "2" smd rect
			(at 0 0.889)
			(size 0.508 0.508)
			(layers "F.Cu" "F.Mask" "F.Paste")
			(net "GND")
		)
		(zone
			(layer "F.Cu")
			(hatch none 0.5)
			(connect_pads
				(clearance 0)
			)
			(min_thickness 0.25)
			(keepout
				(tracks allowed)
				(vias not_allowed)
				(pads allowed)
				(copperpour not_allowed)
				(footprints allowed)
			)
			(placement
				(enabled no)
				(sheetname "")
			)
			(fill
				(thermal_gap 0.5)
				(thermal_bridge_width 0.5)
				(island_removal_mode 0)
			)
			(polygon
				(pts
					(xy 191.643 -3.4925) (xy 192.151 -3.4925) (xy 192.151 -3.1115) (xy 191.643 -3.1115)
				)
			)
		)
		(zone
			(layer "F.Cu")
			(hatch none 0.5)
			(connect_pads
				(clearance 0)
			)
			(min_thickness 0.25)
			(keepout
				(tracks not_allowed)
				(vias allowed)
				(pads allowed)
				(copperpour not_allowed)
				(footprints allowed)
			)
			(placement
				(enabled no)
				(sheetname "")
			)
			(fill
				(thermal_gap 0.5)
				(thermal_bridge_width 0.5)
				(island_removal_mode 0)
			)
			(polygon
				(pts
					(xy 191.643 -3.1115) (xy 192.151 -3.1115) (xy 192.151 -3.4925) (xy 191.643 -3.4925)
				)
			)
		)
	)
	(footprint ""
		(layer "F.Cu")
		(at 440.055 -140.716 90)
		(property "Reference" "R25W177"
			(at -0.8382 -0.67818 90)
			(unlocked yes)
			(layer "F.SilkS")
			(effects
				(font
					(size 0.4064 0.254)
					(thickness 0.1524)
				)
				(justify left)
			)
		)
		(property "Value" ""
			(at 0 0 90)
			(layer "F.Fab")
			(effects
				(font
					(size 1.27 1.27)
				)
			)
		)
		(duplicate_pad_numbers_are_jumpers no)
		(fp_poly
			(pts
				(xy -0.2794 -0.1016) (xy 0.2794 -0.1016) (xy 0.2794 0.9906) (xy -0.2794 0.9906)
			)
			(stroke
				(width 0)
				(type default)
			)
			(fill no)
			(layer "F.CrtYd")
		)
		(fp_line
			(start 0.2794 -0.1016)
			(end -0.2794 -0.1016)
			(stroke
				(width 0.1)
				(type default)
			)
			(layer "F.Fab")
		)
		(fp_line
			(start -0.2794 -0.1016)
			(end -0.2794 0.9906)
			(stroke
				(width 0.1)
				(type default)
			)
			(layer "F.Fab")
		)
		(fp_line
			(start 0.2794 0.9906)
			(end 0.2794 -0.1016)
			(stroke
				(width 0.1)
				(type default)
			)
			(layer "F.Fab")
		)
		(fp_line
			(start -0.2794 0.9906)
			(end 0.2794 0.9906)
			(stroke
				(width 0.1)
				(type default)
			)
			(layer "F.Fab")
		)
		(pad "1" smd rect
			(at 0 0 90)
			(size 0.508 0.508)
			(layers "F.Cu" "F.Mask" "F.Paste")
			(net "P3V3_STBY")
		)
		(pad "2" smd rect
			(at 0 0.889 90)
			(size 0.508 0.508)
			(layers "F.Cu" "F.Mask" "F.Paste")
			(net "BMC_PREQ_BUF_N")
		)
		(zone
			(layer "F.Cu")
			(hatch none 0.5)
			(connect_pads
				(clearance 0)
			)
			(min_thickness 0.25)
			(keepout
				(tracks allowed)
				(vias not_allowed)
				(pads allowed)
				(copperpour not_allowed)
				(footprints allowed)
			)
			(placement
				(enabled no)
				(sheetname "")
			)
			(fill
				(thermal_gap 0.5)
				(thermal_bridge_width 0.5)
				(island_removal_mode 0)
			)
			(polygon
				(pts
					(xy 440.309 -140.462) (xy 440.309 -140.97) (xy 440.69 -140.97) (xy 440.69 -140.462)
				)
			)
		)
		(zone
			(layer "F.Cu")
			(hatch none 0.5)
			(connect_pads
				(clearance 0)
			)
			(min_thickness 0.25)
			(keepout
				(tracks not_allowed)
				(vias allowed)
				(pads allowed)
				(copperpour not_allowed)
				(footprints allowed)
			)
			(placement
				(enabled no)
				(sheetname "")
			)
			(fill
				(thermal_gap 0.5)
				(thermal_bridge_width 0.5)
				(island_removal_mode 0)
			)
			(polygon
				(pts
					(xy 440.69 -140.462) (xy 440.69 -140.97) (xy 440.309 -140.97) (xy 440.309 -140.462)
				)
			)
		)
	)
	(footprint ""
		(layer "F.Cu")
		(at 370.332 -136.4615 180)
		(property "Reference" "R7A14"
			(at 0 0 180)
			(layer "F.SilkS")
			(hide yes)
			(effects
				(font
					(size 1.27 1.27)
				)
			)
		)
		(property "Value" ""
			(at 0 0 180)
			(layer "F.Fab")
			(effects
				(font
					(size 1.27 1.27)
				)
			)
		)
		(duplicate_pad_numbers_are_jumpers no)
		(fp_poly
			(pts
				(xy -0.2794 -0.1016) (xy 0.2794 -0.1016) (xy 0.2794 0.9906) (xy -0.2794 0.9906)
			)
			(stroke
				(width 0)
				(type default)
			)
			(fill no)
			(layer "F.CrtYd")
		)
		(fp_line
			(start 0.2794 0.9906)
			(end 0.2794 -0.1016)
			(stroke
				(width 0.1)
				(type default)
			)
			(layer "F.Fab")
		)
		(fp_line
			(start 0.2794 -0.1016)
			(end -0.2794 -0.1016)
			(stroke
				(width 0.1)
				(type default)
			)
			(layer "F.Fab")
		)
		(fp_line
			(start -0.2794 0.9906)
			(end 0.2794 0.9906)
			(stroke
				(width 0.1)
				(type default)
			)
			(layer "F.Fab")
		)
		(fp_line
			(start -0.2794 -0.1016)
			(end -0.2794 0.9906)
			(stroke
				(width 0.1)
				(type default)
			)
			(layer "F.Fab")
		)
		(pad "1" smd rect
			(at 0 0 180)
			(size 0.508 0.508)
			(layers "F.Cu" "F.Mask" "F.Paste")
			(net "VSENSE_PVNN_PCH_STBY_FPK")
		)
		(pad "2" smd rect
			(at 0 0.889 180)
			(size 0.508 0.508)
			(layers "F.Cu" "F.Mask" "F.Paste")
			(net "VSENSE_PVNN_PCH_STBY_AVSP")
		)
		(zone
			(layer "F.Cu")
			(hatch none 0.5)
			(connect_pads
				(clearance 0)
			)
			(min_thickness 0.25)
			(keepout
				(tracks not_allowed)
				(vias allowed)
				(pads allowed)
				(copperpour not_allowed)
				(footprints allowed)
			)
			(placement
				(enabled no)
				(sheetname "")
			)
			(fill
				(thermal_gap 0.5)
				(thermal_bridge_width 0.5)
				(island_removal_mode 0)
			)
			(polygon
				(pts
					(xy 370.586 -137.0965) (xy 370.078 -137.0965) (xy 370.078 -136.7155) (xy 370.586 -136.7155)
				)
			)
		)
		(zone
			(layer "F.Cu")
			(hatch none 0.5)
			(connect_pads
				(clearance 0)
			)
			(min_thickness 0.25)
			(keepout
				(tracks allowed)
				(vias not_allowed)
				(pads allowed)
				(copperpour not_allowed)
				(footprints allowed)
			)
			(placement
				(enabled no)
				(sheetname "")
			)
			(fill
				(thermal_gap 0.5)
				(thermal_bridge_width 0.5)
				(island_removal_mode 0)
			)
			(polygon
				(pts
					(xy 370.586 -136.7155) (xy 370.078 -136.7155) (xy 370.078 -137.0965) (xy 370.586 -137.0965)
				)
			)
		)
	)
)
